(kicad_pcb
	(version 20260206)
	(generator "pcbnew")
	(generator_version "10.0")
	(general
		(thickness 1.6)
		(legacy_teardrops no)
	)
	(paper "A4")
	(title_block
		(title "Bryce Canyon_R.DPB_16317-1_OCP.brd")
		(comment 1 "Bryce Canyon / footprints 2070-2078 of 2099")
	)
	(layers
		(0 "F.Cu" signal "TOP")
		(4 "In1.Cu" signal "L2GND")
		(6 "In2.Cu" signal "L3")
		(8 "In3.Cu" signal "L4VCC")
		(10 "In4.Cu" signal "L5VCC")
		(12 "In5.Cu" signal "L6")
		(14 "In6.Cu" signal "L7GND")
		(2 "B.Cu" signal "BOTTOM")
		(9 "F.Adhes" user "F.Adhesive")
		(11 "B.Adhes" user "B.Adhesive")
		(13 "F.Paste" user "Package Geometry/Pastemask Top")
		(15 "B.Paste" user "Package Geometry/Pastemask Bottom")
		(5 "F.SilkS" user "Ref Des/Silkscreen Top")
		(7 "B.SilkS" user "Ref Des/Silkscreen Bottom")
		(1 "F.Mask" user "Board Geometry/Soldermask Top")
		(3 "B.Mask" user "Board Geometry/Soldermask Bottom")
		(17 "Dwgs.User" user "User.Drawings")
		(19 "Cmts.User" user "User.Comments")
		(21 "Eco1.User" user "User.Eco1")
		(23 "Eco2.User" user "User.Eco2")
		(25 "Edge.Cuts" user "Board Geometry/Outline")
		(27 "Margin" user)
		(31 "F.CrtYd" user "Package Geometry/Place Bound Top")
		(29 "B.CrtYd" user "Package Geometry/Place Bound Bottom")
		(35 "F.Fab" user "Ref Des/Assembly Top")
		(33 "B.Fab" user "Ref Des/Assembly Bottom")
	)
	(footprint ""
		(layer "B.Cu")
		(at 32.293814 -229.093776 180)
		(property "Reference" "C627"
			(at 0 0 0)
			(layer "B.SilkS")
			(hide yes)
			(effects
				(font
					(size 1.27 1.27)
				)
				(justify mirror)
			)
		)
		(property "Value" "SCD1U50V3KX-GP"
			(at 0 -2.8194 180)
			(unlocked yes)
			(layer "B.Fab")
			(hide yes)
			(effects
				(font
					(size 1.016 1.016)
					(thickness 0.1524)
				)
				(justify mirror)
			)
		)
		(property "Device Type" "C603H36"
			(at 0 -4.3434 180)
			(unlocked yes)
			(layer "B.Fab")
			(hide yes)
			(effects
				(font
					(size 1.016 1.016)
					(thickness 0.1524)
				)
				(justify mirror)
			)
		)
		(duplicate_pad_numbers_are_jumpers no)
		(fp_line
			(start -0.508 0)
			(end 0.508 0)
			(stroke
				(width 0.2032)
				(type default)
			)
			(layer "B.SilkS")
		)
		(fp_rect
			(start 0.5842 1.3335)
			(end -0.5842 -1.3335)
			(stroke
				(width 0)
				(type default)
			)
			(fill no)
			(layer "B.CrtYd")
		)
		(fp_rect
			(start 0.5842 1.3335)
			(end -0.5842 -1.3335)
			(stroke
				(width 0)
				(type default)
			)
			(fill no)
			(layer "B.Fab")
		)
		(pad "1" smd custom
			(at 0 -0.762)
			(size 0.2159 0.2159)
			(layers "B.Cu" "B.Mask" "B.Paste")
			(net "P5V_B_1")
			(options
				(clearance outline)
				(anchor circle)
			)
			(primitives
				(gr_poly
					(pts
						(arc
							(start -0.3302 0.4318)
							(mid -0.402042 0.402042)
							(end -0.4318 0.3302)
						)
						(arc
							(start -0.4318 -0.3302)
							(mid -0.402042 -0.402042)
							(end -0.3302 -0.4318)
						)
						(arc
							(start 0.3302 -0.4318)
							(mid 0.402042 -0.402042)
							(end 0.4318 -0.3302)
						)
						(arc
							(start 0.4318 0.3302)
							(mid 0.402042 0.402042)
							(end 0.3302 0.4318)
						)
					)
					(width 0)
					(fill yes)
				)
			)
		)
		(pad "2" smd custom
			(at 0 0.762)
			(size 0.2159 0.2159)
			(layers "B.Cu" "B.Mask" "B.Paste")
			(net "P5V_B_1_LL_R")
			(options
				(clearance outline)
				(anchor circle)
			)
			(primitives
				(gr_poly
					(pts
						(arc
							(start -0.3302 0.4318)
							(mid -0.402042 0.402042)
							(end -0.4318 0.3302)
						)
						(arc
							(start -0.4318 -0.3302)
							(mid -0.402042 -0.402042)
							(end -0.3302 -0.4318)
						)
						(arc
							(start 0.3302 -0.4318)
							(mid 0.402042 -0.402042)
							(end 0.4318 -0.3302)
						)
						(arc
							(start 0.4318 0.3302)
							(mid 0.402042 0.402042)
							(end 0.3302 0.4318)
						)
					)
					(width 0)
					(fill yes)
				)
			)
		)
	)
	(footprint ""
		(layer "B.Cu")
		(at 484.317802 -228.35235 180)
		(property "Reference" "C669"
			(at 0 0 0)
			(layer "B.SilkS")
			(hide yes)
			(effects
				(font
					(size 1.27 1.27)
				)
				(justify mirror)
			)
		)
		(property "Value" "SC10U16V5KX-7-GP-U"
			(at 0.0762 -6.1214 180)
			(unlocked yes)
			(layer "B.Fab")
			(hide yes)
			(effects
				(font
					(size 1.016 1.016)
					(thickness 0.1524)
				)
				(justify mirror)
			)
		)
		(property "Device Type" "C805H58"
			(at 0.0762 -8.1534 180)
			(unlocked yes)
			(layer "B.Fab")
			(hide yes)
			(effects
				(font
					(size 1.016 1.016)
					(thickness 0.1524)
				)
				(justify mirror)
			)
		)
		(duplicate_pad_numbers_are_jumpers no)
		(fp_line
			(start -0.635 0)
			(end 0.635 0)
			(stroke
				(width 0.508)
				(type default)
			)
			(layer "B.SilkS")
		)
		(fp_rect
			(start 0.9652 1.778)
			(end -0.9652 -1.778)
			(stroke
				(width 0)
				(type default)
			)
			(fill no)
			(layer "B.CrtYd")
		)
		(fp_poly
			(pts
				(xy 0.9652 -1.778) (xy -0.9652 -1.778) (xy -0.9652 1.778) (xy 0.9652 1.778)
			)
			(stroke
				(width 0)
				(type default)
			)
			(fill no)
			(layer "B.Fab")
		)
		(pad "1" smd rect
			(at 0 -0.9652)
			(size 1.397 1.143)
			(layers "B.Cu" "B.Mask" "B.Paste")
			(net "P5V_B_3")
		)
		(pad "2" smd rect
			(at 0 0.9652)
			(size 1.397 1.143)
			(layers "B.Cu" "B.Mask" "B.Paste")
			(net "GND")
		)
	)
	(footprint ""
		(layer "B.Cu")
		(at 206.756 -338.582 90)
		(property "Reference" "R1017"
			(at 0 0 90)
			(layer "B.SilkS")
			(hide yes)
			(effects
				(font
					(size 1.27 1.27)
				)
				(justify mirror)
			)
		)
		(property "Value" "10R5F-1-GP"
			(at 0 -8.9535 90)
			(unlocked yes)
			(layer "B.Fab")
			(hide yes)
			(effects
				(font
					(size 1.27 1.016)
					(thickness 0.1524)
				)
				(justify mirror)
			)
		)
		(property "Device Type" "R805H24"
			(at 0 -10.6299 90)
			(unlocked yes)
			(layer "B.Fab")
			(hide yes)
			(effects
				(font
					(size 1.27 1.016)
					(thickness 0.1524)
				)
				(justify mirror)
			)
		)
		(duplicate_pad_numbers_are_jumpers no)
		(fp_line
			(start 0.889 -1.7018)
			(end 0.889 0.2794)
			(stroke
				(width 0.1524)
				(type default)
			)
			(layer "B.SilkS")
		)
		(fp_line
			(start -0.889 -1.7018)
			(end 0.889 -1.7018)
			(stroke
				(width 0.1524)
				(type default)
			)
			(layer "B.SilkS")
		)
		(fp_line
			(start -0.889 -1.7018)
			(end -0.889 -0.381)
			(stroke
				(width 0.1524)
				(type default)
			)
			(layer "B.SilkS")
		)
		(fp_line
			(start 0.889 0.0762)
			(end 0.889 1.7018)
			(stroke
				(width 0.1524)
				(type default)
			)
			(layer "B.SilkS")
		)
		(fp_line
			(start 0.889 1.7018)
			(end -0.889 1.7018)
			(stroke
				(width 0.1524)
				(type default)
			)
			(layer "B.SilkS")
		)
		(fp_line
			(start -0.889 1.7018)
			(end -0.889 -0.508)
			(stroke
				(width 0.1524)
				(type default)
			)
			(layer "B.SilkS")
		)
		(fp_poly
			(pts
				(xy -0.9652 -1.778) (xy -0.9652 1.778) (xy 0.9652 1.778) (xy 0.9652 -1.778)
			)
			(stroke
				(width 0)
				(type default)
			)
			(fill no)
			(layer "B.CrtYd")
		)
		(fp_rect
			(start 0.9652 1.778)
			(end -0.9652 -1.778)
			(stroke
				(width 0)
				(type default)
			)
			(fill no)
			(layer "B.Fab")
		)
		(pad "1" smd rect
			(at 0 -0.9652 270)
			(size 1.397 1.143)
			(layers "B.Cu" "B.Mask" "B.Paste")
			(net "MB0_12V_CTRL_GATE3")
		)
		(pad "2" smd rect
			(at 0 0.9652 270)
			(size 1.397 1.143)
			(layers "B.Cu" "B.Mask" "B.Paste")
			(net "MB0_CM_GATE_R")
		)
	)
	(footprint ""
		(layer "B.Cu")
		(at 443.895988 -119.309642 -90)
		(property "Reference" "R1163"
			(at 0 0 90)
			(layer "B.SilkS")
			(hide yes)
			(effects
				(font
					(size 1.27 1.27)
				)
				(justify mirror)
			)
		)
		(property "Value" "10R3F-GP"
			(at 0.0254 -2.5146 270)
			(unlocked yes)
			(layer "B.Fab")
			(hide yes)
			(effects
				(font
					(size 1.016 1.016)
					(thickness 0.1524)
				)
				(justify mirror)
			)
		)
		(property "Device Type" "R603H22"
			(at 0.0254 -4.0386 270)
			(unlocked yes)
			(layer "B.Fab")
			(hide yes)
			(effects
				(font
					(size 1.016 1.016)
					(thickness 0.1524)
				)
				(justify mirror)
			)
		)
		(duplicate_pad_numbers_are_jumpers no)
		(fp_line
			(start -0.2032 0)
			(end -0.4826 0)
			(stroke
				(width 0.2032)
				(type default)
			)
			(layer "B.SilkS")
		)
		(fp_line
			(start 0.4826 0)
			(end 0.2032 0)
			(stroke
				(width 0.2032)
				(type default)
			)
			(layer "B.SilkS")
		)
		(fp_rect
			(start 0.5842 1.3335)
			(end -0.5842 -1.3335)
			(stroke
				(width 0)
				(type default)
			)
			(fill no)
			(layer "B.CrtYd")
		)
		(fp_rect
			(start 0.5842 1.3335)
			(end -0.5842 -1.3335)
			(stroke
				(width 0)
				(type default)
			)
			(fill no)
			(layer "B.Fab")
		)
		(pad "1" smd custom
			(at 0 -0.762 90)
			(size 0.2159 0.2159)
			(layers "B.Cu" "B.Mask" "B.Paste")
			(net "P5V_B_4_CC")
			(options
				(clearance outline)
				(anchor circle)
			)
			(primitives
				(gr_poly
					(pts
						(arc
							(start -0.3302 0.4318)
							(mid -0.402042 0.402042)
							(end -0.4318 0.3302)
						)
						(arc
							(start -0.4318 -0.3302)
							(mid -0.402042 -0.402042)
							(end -0.3302 -0.4318)
						)
						(arc
							(start 0.3302 -0.4318)
							(mid 0.402042 -0.402042)
							(end 0.4318 -0.3302)
						)
						(arc
							(start 0.4318 0.3302)
							(mid 0.402042 0.402042)
							(end 0.3302 0.4318)
						)
					)
					(width 0)
					(fill yes)
				)
			)
		)
		(pad "2" smd custom
			(at 0 0.762 90)
			(size 0.2159 0.2159)
			(layers "B.Cu" "B.Mask" "B.Paste")
			(net "P5V_B_4_VFB_R")
			(options
				(clearance outline)
				(anchor circle)
			)
			(primitives
				(gr_poly
					(pts
						(arc
							(start -0.3302 0.4318)
							(mid -0.402042 0.402042)
							(end -0.4318 0.3302)
						)
						(arc
							(start -0.4318 -0.3302)
							(mid -0.402042 -0.402042)
							(end -0.3302 -0.4318)
						)
						(arc
							(start 0.3302 -0.4318)
							(mid 0.402042 -0.402042)
							(end 0.4318 -0.3302)
						)
						(arc
							(start 0.4318 0.3302)
							(mid 0.402042 0.402042)
							(end 0.3302 0.4318)
						)
					)
					(width 0)
					(fill yes)
				)
			)
		)
	)
	(footprint ""
		(layer "B.Cu")
		(at 222.631 -355.473 180)
		(property "Reference" "C516"
			(at 0 0 0)
			(layer "B.SilkS")
			(hide yes)
			(effects
				(font
					(size 1.27 1.27)
				)
				(justify mirror)
			)
		)
		(property "Value" "SC22U25V6KX-2-GP-U"
			(at 2.860802 -5.279644 180)
			(unlocked yes)
			(layer "B.Fab")
			(hide yes)
			(effects
				(font
					(size 1.016 1.016)
					(thickness 0.1524)
				)
				(justify mirror)
			)
		)
		(property "Device Type" "C1206-TO0D3H75"
			(at 2.860802 -6.803644 180)
			(unlocked yes)
			(layer "B.Fab")
			(hide yes)
			(effects
				(font
					(size 1.016 1.016)
					(thickness 0.1524)
				)
				(justify mirror)
			)
		)
		(duplicate_pad_numbers_are_jumpers no)
		(fp_line
			(start 1.3081 2.3749)
			(end 1.3081 -2.3749)
			(stroke
				(width 0.1524)
				(type default)
			)
			(layer "B.SilkS")
		)
		(fp_line
			(start 1.3081 -2.3749)
			(end -1.3081 -2.3749)
			(stroke
				(width 0.1524)
				(type default)
			)
			(layer "B.SilkS")
		)
		(fp_line
			(start -1.3081 2.3749)
			(end 1.3081 2.3749)
			(stroke
				(width 0.1524)
				(type default)
			)
			(layer "B.SilkS")
		)
		(fp_line
			(start -1.3081 -2.3749)
			(end -1.3081 2.3749)
			(stroke
				(width 0.1524)
				(type default)
			)
			(layer "B.SilkS")
		)
		(fp_rect
			(start 0.8001 1.6002)
			(end -0.8001 -1.6002)
			(stroke
				(width 0)
				(type default)
			)
			(fill no)
			(layer "B.CrtYd")
		)
		(fp_poly
			(pts
				(xy 1.5621 2.4511) (xy 1.5621 1.6002) (xy -0.8001 1.6002) (xy -0.8001 -1.6002) (xy 0.8001 -1.6002)
				(xy 0.8001 1.5875) (xy 1.5621 1.5875) (xy 1.5621 -2.4511) (xy -1.5621 -2.4511) (xy -1.5621 2.4511)
			)
			(stroke
				(width 0)
				(type default)
			)
			(fill no)
			(layer "B.CrtYd")
		)
		(fp_rect
			(start 1.5621 2.4511)
			(end -1.5621 -2.4511)
			(stroke
				(width 0)
				(type default)
			)
			(fill no)
			(layer "B.Fab")
		)
		(pad "1" smd rect
			(at 0 -1.392936)
			(size 2.1082 1.4478)
			(layers "B.Cu" "B.Mask" "B.Paste")
			(net "P12V_IN")
		)
		(pad "2" smd rect
			(at 0 1.392936)
			(size 2.1082 1.4478)
			(layers "B.Cu" "B.Mask" "B.Paste")
			(net "GND")
		)
	)
	(footprint ""
		(layer "B.Cu")
		(at 424.906186 -112.193578 180)
		(property "Reference" "R1156"
			(at 0 0 0)
			(layer "B.SilkS")
			(hide yes)
			(effects
				(font
					(size 1.27 1.27)
				)
				(justify mirror)
			)
		)
		(property "Value" "2D2R3-1-U-GP"
			(at 0.0254 -2.5146 180)
			(unlocked yes)
			(layer "B.Fab")
			(hide yes)
			(effects
				(font
					(size 1.016 1.016)
					(thickness 0.1524)
				)
				(justify mirror)
			)
		)
		(property "Device Type" "R603H22"
			(at 0.0254 -4.0386 180)
			(unlocked yes)
			(layer "B.Fab")
			(hide yes)
			(effects
				(font
					(size 1.016 1.016)
					(thickness 0.1524)
				)
				(justify mirror)
			)
		)
		(duplicate_pad_numbers_are_jumpers no)
		(fp_line
			(start 0.4826 0)
			(end 0.2032 0)
			(stroke
				(width 0.2032)
				(type default)
			)
			(layer "B.SilkS")
		)
		(fp_line
			(start -0.2032 0)
			(end -0.4826 0)
			(stroke
				(width 0.2032)
				(type default)
			)
			(layer "B.SilkS")
		)
		(fp_rect
			(start 0.5842 1.3335)
			(end -0.5842 -1.3335)
			(stroke
				(width 0)
				(type default)
			)
			(fill no)
			(layer "B.CrtYd")
		)
		(fp_rect
			(start 0.5842 1.3335)
			(end -0.5842 -1.3335)
			(stroke
				(width 0)
				(type default)
			)
			(fill no)
			(layer "B.Fab")
		)
		(pad "1" smd custom
			(at 0 -0.762)
			(size 0.2159 0.2159)
			(layers "B.Cu" "B.Mask" "B.Paste")
			(net "P12V_B")
			(options
				(clearance outline)
				(anchor circle)
			)
			(primitives
				(gr_poly
					(pts
						(arc
							(start -0.3302 0.4318)
							(mid -0.402042 0.402042)
							(end -0.4318 0.3302)
						)
						(arc
							(start -0.4318 -0.3302)
							(mid -0.402042 -0.402042)
							(end -0.3302 -0.4318)
						)
						(arc
							(start 0.3302 -0.4318)
							(mid 0.402042 -0.402042)
							(end 0.4318 -0.3302)
						)
						(arc
							(start 0.4318 0.3302)
							(mid 0.402042 0.402042)
							(end 0.3302 0.4318)
						)
					)
					(width 0)
					(fill yes)
				)
			)
		)
		(pad "2" smd custom
			(at 0 0.762)
			(size 0.2159 0.2159)
			(layers "B.Cu" "B.Mask" "B.Paste")
			(net "P12V_B_4_VDD_U34")
			(options
				(clearance outline)
				(anchor circle)
			)
			(primitives
				(gr_poly
					(pts
						(arc
							(start -0.3302 0.4318)
							(mid -0.402042 0.402042)
							(end -0.4318 0.3302)
						)
						(arc
							(start -0.4318 -0.3302)
							(mid -0.402042 -0.402042)
							(end -0.3302 -0.4318)
						)
						(arc
							(start 0.3302 -0.4318)
							(mid 0.402042 -0.402042)
							(end 0.4318 -0.3302)
						)
						(arc
							(start 0.4318 0.3302)
							(mid 0.402042 0.402042)
							(end 0.3302 0.4318)
						)
					)
					(width 0)
					(fill yes)
				)
			)
		)
	)
	(footprint ""
		(layer "B.Cu")
		(at 429.097186 -112.701578 180)
		(property "Reference" "C672"
			(at 0 0 0)
			(layer "B.SilkS")
			(hide yes)
			(effects
				(font
					(size 1.27 1.27)
				)
				(justify mirror)
			)
		)
		(property "Value" "SC10U16V5KX-7-GP-U"
			(at 0.0762 -6.1214 180)
			(unlocked yes)
			(layer "B.Fab")
			(hide yes)
			(effects
				(font
					(size 1.016 1.016)
					(thickness 0.1524)
				)
				(justify mirror)
			)
		)
		(property "Device Type" "C805H58"
			(at 0.0762 -8.1534 180)
			(unlocked yes)
			(layer "B.Fab")
			(hide yes)
			(effects
				(font
					(size 1.016 1.016)
					(thickness 0.1524)
				)
				(justify mirror)
			)
		)
		(duplicate_pad_numbers_are_jumpers no)
		(fp_line
			(start -0.635 0)
			(end 0.635 0)
			(stroke
				(width 0.508)
				(type default)
			)
			(layer "B.SilkS")
		)
		(fp_rect
			(start 0.9652 1.778)
			(end -0.9652 -1.778)
			(stroke
				(width 0)
				(type default)
			)
			(fill no)
			(layer "B.CrtYd")
		)
		(fp_poly
			(pts
				(xy 0.9652 -1.778) (xy -0.9652 -1.778) (xy -0.9652 1.778) (xy 0.9652 1.778)
			)
			(stroke
				(width 0)
				(type default)
			)
			(fill no)
			(layer "B.Fab")
		)
		(pad "1" smd rect
			(at 0 -0.9652)
			(size 1.397 1.143)
			(layers "B.Cu" "B.Mask" "B.Paste")
			(net "P12V_B_4_VIN_U34")
		)
		(pad "2" smd rect
			(at 0 0.9652)
			(size 1.397 1.143)
			(layers "B.Cu" "B.Mask" "B.Paste")
			(net "GND")
		)
	)
	(footprint ""
		(layer "B.Cu")
		(at 224.55124 -329.065128)
		(property "Reference" "C512"
			(at 0 0 0)
			(layer "B.SilkS")
			(hide yes)
			(effects
				(font
					(size 1.27 1.27)
				)
				(justify mirror)
			)
		)
		(property "Value" "SC22U25V6KX-2-GP-U"
			(at 2.860802 -5.279644 0)
			(unlocked yes)
			(layer "B.Fab")
			(hide yes)
			(effects
				(font
					(size 1.016 1.016)
					(thickness 0.1524)
				)
				(justify mirror)
			)
		)
		(property "Device Type" "C1206-TO0D3H75"
			(at 2.860802 -6.803644 0)
			(unlocked yes)
			(layer "B.Fab")
			(hide yes)
			(effects
				(font
					(size 1.016 1.016)
					(thickness 0.1524)
				)
				(justify mirror)
			)
		)
		(duplicate_pad_numbers_are_jumpers no)
		(fp_line
			(start -1.3081 -2.3749)
			(end -1.3081 2.3749)
			(stroke
				(width 0.1524)
				(type default)
			)
			(layer "B.SilkS")
		)
		(fp_line
			(start -1.3081 2.3749)
			(end 1.3081 2.3749)
			(stroke
				(width 0.1524)
				(type default)
			)
			(layer "B.SilkS")
		)
		(fp_line
			(start 1.3081 -2.3749)
			(end -1.3081 -2.3749)
			(stroke
				(width 0.1524)
				(type default)
			)
			(layer "B.SilkS")
		)
		(fp_line
			(start 1.3081 2.3749)
			(end 1.3081 -2.3749)
			(stroke
				(width 0.1524)
				(type default)
			)
			(layer "B.SilkS")
		)
		(fp_rect
			(start 0.8001 1.6002)
			(end -0.8001 -1.6002)
			(stroke
				(width 0)
				(type default)
			)
			(fill no)
			(layer "B.CrtYd")
		)
		(fp_poly
			(pts
				(xy 1.5621 2.4511) (xy 1.5621 1.6002) (xy -0.8001 1.6002) (xy -0.8001 -1.6002) (xy 0.8001 -1.6002)
				(xy 0.8001 1.5875) (xy 1.5621 1.5875) (xy 1.5621 -2.4511) (xy -1.5621 -2.4511) (xy -1.5621 2.4511)
			)
			(stroke
				(width 0)
				(type default)
			)
			(fill no)
			(layer "B.CrtYd")
		)
		(fp_rect
			(start 1.5621 2.4511)
			(end -1.5621 -2.4511)
			(stroke
				(width 0)
				(type default)
			)
			(fill no)
			(layer "B.Fab")
		)
		(pad "1" smd rect
			(at 0 -1.392936 180)
			(size 2.1082 1.4478)
			(layers "B.Cu" "B.Mask" "B.Paste")
			(net "P12V_IN")
		)
		(pad "2" smd rect
			(at 0 1.392936 180)
			(size 2.1082 1.4478)
			(layers "B.Cu" "B.Mask" "B.Paste")
			(net "GND")
		)
	)
	(footprint ""
		(layer "B.Cu")
		(at 241.935 -286.004 180)
		(property "Reference" "C705"
			(at 0 0 0)
			(layer "B.SilkS")
			(hide yes)
			(effects
				(font
					(size 1.27 1.27)
				)
				(justify mirror)
			)
		)
		(property "Value" "SC10U6D3V5KX-4GP"
			(at 0.0762 -6.1214 180)
			(unlocked yes)
			(layer "B.Fab")
			(hide yes)
			(effects
				(font
					(size 1.016 1.016)
					(thickness 0.1524)
				)
				(justify mirror)
			)
		)
		(property "Device Type" "C805H58"
			(at 0.0762 -8.1534 180)
			(unlocked yes)
			(layer "B.Fab")
			(hide yes)
			(effects
				(font
					(size 1.016 1.016)
					(thickness 0.1524)
				)
				(justify mirror)
			)
		)
		(duplicate_pad_numbers_are_jumpers no)
		(fp_line
			(start -0.635 0)
			(end 0.635 0)
			(stroke
				(width 0.508)
				(type default)
			)
			(layer "B.SilkS")
		)
		(fp_rect
			(start 0.9652 1.778)
			(end -0.9652 -1.778)
			(stroke
				(width 0)
				(type default)
			)
			(fill no)
			(layer "B.CrtYd")
		)
		(fp_poly
			(pts
				(xy 0.9652 -1.778) (xy -0.9652 -1.778) (xy -0.9652 1.778) (xy 0.9652 1.778)
			)
			(stroke
				(width 0)
				(type default)
			)
			(fill no)
			(layer "B.Fab")
		)
		(pad "1" smd rect
			(at 0 -0.9652)
			(size 1.397 1.143)
			(layers "B.Cu" "B.Mask" "B.Paste")
			(net "P3V3_STBY_B")
		)
		(pad "2" smd rect
			(at 0 0.9652)
			(size 1.397 1.143)
			(layers "B.Cu" "B.Mask" "B.Paste")
			(net "GND")
		)
	)
)
